#ISCELL
  mstr_misc dns *
  *
#ISCELL
  pure_quanta quanta_title_block_c *
  *
#ISCELL
  pure_quanta_power design_note *
  *
#ISCELL
  standard offpage *
  page28_i1
#ISCELL
  standard offpage *
  page28_i10
#CELL
  pure_quanta q_res *
  page28_i100
#ISCELL
  standard offpage *
  page28_i101
#ISCELL
  pure_quanta_power universal_gnd *
  page28_i102
#CELL
  pure_quanta q_xtal_4p_13bi_24gnd *
  page28_i103
#CELL
  pure_quanta q_res *
  page28_i104
#ISCELL
  pure_quanta_power universal_gnd *
  page28_i105
#ISCELL
  pure_quanta_power universal_gnd *
  page28_i106
#ISCELL
  standard offpage *
  page28_i108
#ISCELL
  standard offpage *
  page28_i109
#ISCELL
  standard offpage *
  page28_i11
#ISCELL
  standard offpage *
  page28_i112
#ISCELL
  standard offpage *
  page28_i113
#ISCELL
  standard offpage *
  page28_i114
#ISCELL
  standard offpage *
  page28_i115
#ISCELL
  standard offpage *
  page28_i116
#ISCELL
  standard offpage *
  page28_i117
#ISCELL
  standard offpage *
  page28_i118
#ISCELL
  standard offpage *
  page28_i119
#ISCELL
  standard offpage *
  page28_i12
#ISCELL
  standard offpage *
  page28_i120
#ISCELL
  standard offpage *
  page28_i124
#ISCELL
  standard offpage *
  page28_i125
#ISCELL
  standard offpage *
  page28_i126
#ISCELL
  standard offpage *
  page28_i127
#ISCELL
  standard offpage *
  page28_i128
#ISCELL
  standard offpage *
  page28_i129
#ISCELL
  standard offpage *
  page28_i13
#ISCELL
  standard offpage *
  page28_i130
#ISCELL
  standard offpage *
  page28_i131
#ISCELL
  standard offpage *
  page28_i132
#ISCELL
  standard offpage *
  page28_i133
#ISCELL
  standard offpage *
  page28_i134
#CELL
  pure_quanta q_res *
  page28_i135
#CELL
  pure_quanta q_res *
  page28_i136
#ISCELL
  pure_quanta_power universal_gnd *
  page28_i137
#CELL
  pure_quanta q_crystal *
  page28_i140
#ISCELL
  pure_quanta_power universal_gnd *
  page28_i141
#ISCELL
  standard offpage *
  page28_i143
#ISCELL
  standard offpage *
  page28_i144
#ISCELL
  standard offpage *
  page28_i145
#ISCELL
  standard offpage *
  page28_i146
#ISCELL
  standard offpage *
  page28_i147
#ISCELL
  standard offpage *
  page28_i148
#ISCELL
  standard offpage *
  page28_i150
#CELL
  pure_quanta q_res *
  page28_i151
#CELL
  pure_quanta q_res *
  page28_i152
#CELL
  pure_quanta q_res *
  page28_i153
#CELL
  pure_quanta q_res *
  page28_i154
#CELL
  pure_quanta q_res *
  page28_i155
#CELL
  pure_quanta q_res *
  page28_i156
#CELL
  pure_quanta q_res *
  page28_i157
#CELL
  pure_quanta q_res *
  page28_i158
#ISCELL
  standard offpage *
  page28_i159
#ISCELL
  standard offpage *
  page28_i16
#CELL
  pure_quanta q_res *
  page28_i160
#CELL
  pure_quanta q_res *
  page28_i161
#ISCELL
  standard offpage *
  page28_i162
#ISCELL
  standard offpage *
  page28_i163
#ISCELL
  standard offpage *
  page28_i164
#CELL
  pure_quanta q_res *
  page28_i165
#ISCELL
  standard offpage *
  page28_i166
#CELL
  pure_quanta q_res *
  page28_i167
#CELL
  pure_quanta q_res *
  page28_i168
#ISCELL
  standard offpage *
  page28_i169
#ISCELL
  standard offpage *
  page28_i170
#CELL
  pure_quanta q_res *
  page28_i171
#CELL
  pure_quanta q_res *
  page28_i172
#ISCELL
  standard offpage *
  page28_i173
#ISCELL
  standard offpage *
  page28_i174
#ISCELL
  standard offpage *
  page28_i175
#ISCELL
  standard offpage *
  page28_i176
#ISCELL
  standard offpage *
  page28_i177
#ISCELL
  standard offpage *
  page28_i178
#ISCELL
  standard offpage *
  page28_i179
#ISCELL
  standard offpage *
  page28_i18
#ISCELL
  standard offpage *
  page28_i180
#ISCELL
  standard offpage *
  page28_i181
#ISCELL
  standard offpage *
  page28_i182
#ISCELL
  standard offpage *
  page28_i183
#ISCELL
  standard offpage *
  page28_i184
#ISCELL
  standard offpage *
  page28_i185
#ISCELL
  standard offpage *
  page28_i186
#ISCELL
  standard offpage *
  page28_i187
#CELL
  pure_quanta genoa_sp5 *
  page28_i188
#ISCELL
  standard offpage *
  page28_i189
#ISCELL
  standard offpage *
  page28_i19
#ISCELL
  standard offpage *
  page28_i190
#CELL
  pure_quanta q_res *
  page28_i191
#CELL
  pure_quanta q_res *
  page28_i192
#ISCELL
  pure_quanta_power universal_gnd *
  page28_i193
#CELL
  pure_quanta q_cap *
  page28_i194
#CELL
  pure_quanta q_res *
  page28_i195
#ISCELL
  standard offpage *
  page28_i2
#ISCELL
  standard offpage *
  page28_i20
#CELL
  pure_quanta q_res *
  page28_i206
#CELL
  pure_quanta q_res *
  page28_i207
#CELL
  pure_quanta q_res *
  page28_i208
#CELL
  pure_quanta q_res *
  page28_i209
#ISCELL
  standard offpage *
  page28_i21
#CELL
  pure_quanta q_res *
  page28_i210
#ISCELL
  pure_quanta_power vcc_core *
  page28_i211
#CELL
  pure_quanta q_res *
  page28_i212
#CELL
  pure_quanta q_res *
  page28_i213
#CELL
  pure_quanta q_res *
  page28_i214
#ISCELL
  standard offpage *
  page28_i215
#ISCELL
  standard offpage *
  page28_i216
#ISCELL
  standard offpage *
  page28_i217
#ISCELL
  standard offpage *
  page28_i218
#ISCELL
  standard offpage *
  page28_i219
#CELL
  pure_quanta q_res *
  page28_i22
#ISCELL
  standard offpage *
  page28_i220
#CELL
  pure_quanta q_res *
  page28_i221
#CELL
  pure_quanta q_res *
  page28_i222
#ISCELL
  standard offpage *
  page28_i223
#CELL
  pure_quanta q_res *
  page28_i224
#ISCELL
  pure_quanta_power universal_gnd *
  page28_i225
#ISCELL
  standard offpage *
  page28_i226
#ISCELL
  standard offpage *
  page28_i227
#CELL
  pure_quanta q_res *
  page28_i228
#CELL
  pure_quanta q_res *
  page28_i229
#CELL
  pure_quanta q_res *
  page28_i23
#CELL
  pure_quanta q_cap *
  page28_i230
#CELL
  pure_quanta q_cap *
  page28_i231
#CELL
  pure_quanta q_cap *
  page28_i232
#CELL
  pure_quanta q_cap *
  page28_i233
#CELL
  pure_quanta q_res *
  page28_i24
#CELL
  pure_quanta q_res *
  page28_i25
#ISCELL
  pure_quanta_power vcc_core *
  page28_i26
#ISCELL
  pure_quanta_power universal_gnd *
  page28_i27
#CELL
  pure_quanta conn6_hbc1031l200d8h *
  page28_i28
#CELL
  pure_quanta q_res *
  page28_i29
#ISCELL
  standard offpage *
  page28_i3
#CELL
  pure_quanta q_res *
  page28_i30
#ISCELL
  pure_quanta_power universal_power *
  page28_i31
#ISCELL
  pure_quanta_power universal_gnd *
  page28_i32
#CELL
  pure_quanta q_res *
  page28_i33
#CELL
  pure_quanta q_res *
  page28_i34
#ISCELL
  pure_quanta_power universal_gnd *
  page28_i35
#CELL
  pure_quanta q_res *
  page28_i36
#CELL
  pure_quanta q_res *
  page28_i37
#ISCELL
  pure_quanta_power universal_gnd *
  page28_i38
#ISCELL
  pure_quanta_power universal_gnd *
  page28_i39
#ISCELL
  standard offpage *
  page28_i4
#CELL
  pure_quanta q_res *
  page28_i40
#CELL
  pure_quanta q_res *
  page28_i41
#CELL
  pure_quanta q_res *
  page28_i42
#CELL
  pure_quanta q_res *
  page28_i43
#CELL
  pure_quanta q_res *
  page28_i44
#CELL
  pure_quanta q_res *
  page28_i45
#CELL
  pure_quanta q_res *
  page28_i46
#CELL
  pure_quanta q_res *
  page28_i47
#CELL
  pure_quanta q_res *
  page28_i48
#CELL
  pure_quanta q_res *
  page28_i49
#ISCELL
  standard offpage *
  page28_i5
#CELL
  pure_quanta q_res *
  page28_i53
#CELL
  pure_quanta q_res *
  page28_i55
#CELL
  pure_quanta q_res *
  page28_i56
#ISCELL
  pure_quanta_power universal_power *
  page28_i57
#ISCELL
  pure_quanta_power universal_gnd *
  page28_i58
#CELL
  pure_quanta q_res *
  page28_i59
#ISCELL
  standard offpage *
  page28_i6
#CELL
  pure_quanta q_res *
  page28_i60
#ISCELL
  pure_quanta_power universal_gnd *
  page28_i61
#CELL
  pure_quanta q_res *
  page28_i62
#ISCELL
  pure_quanta_power universal_gnd *
  page28_i63
#CELL
  pure_quanta q_res *
  page28_i64
#CELL
  pure_quanta q_res *
  page28_i65
#CELL
  pure_quanta q_res *
  page28_i66
#ISCELL
  pure_quanta_power universal_gnd *
  page28_i68
#CELL
  pure_quanta q_res *
  page28_i69
#ISCELL
  standard offpage *
  page28_i7
#ISCELL
  standard offpage *
  page28_i70
#ISCELL
  standard offpage *
  page28_i71
#ISCELL
  standard offpage *
  page28_i72
#ISCELL
  standard offpage *
  page28_i73
#ISCELL
  pure_quanta_power universal_power *
  page28_i74
#ISCELL
  standard offpage *
  page28_i75
#ISCELL
  standard offpage *
  page28_i76
#ISCELL
  standard offpage *
  page28_i77
#ISCELL
  standard offpage *
  page28_i78
#ISCELL
  standard offpage *
  page28_i79
#ISCELL
  standard offpage *
  page28_i8
#ISCELL
  standard offpage *
  page28_i80
#ISCELL
  standard offpage *
  page28_i81
#ISCELL
  standard offpage *
  page28_i83
#ISCELL
  standard offpage *
  page28_i85
#ISCELL
  standard offpage *
  page28_i86
#ISCELL
  standard offpage *
  page28_i89
#ISCELL
  standard offpage *
  page28_i9
#ISCELL
  standard offpage *
  page28_i90
#ISCELL
  standard offpage *
  page28_i91
#ISCELL
  standard offpage *
  page28_i92
#CELL
  pure_quanta q_res *
  page28_i93
#CELL
  pure_quanta q_res *
  page28_i94
#CELL
  pure_quanta q_res *
  page28_i95
#CELL
  pure_quanta q_res *
  page28_i96
#CELL
  pure_quanta q_res *
  page28_i97
#CELL
  pure_quanta q_res *
  page28_i98
